(kicad_pcb
	(version 20260206)
	(generator "pcbnew")
	(generator_version "10.0")
	(general
		(thickness 1.6)
		(legacy_teardrops no)
	)
	(paper "A4")
	(title_block
		(title "baseboard — 13948-1b.1110WZS1818.brd")
		(comment 1 "Honey Badger (Wiwynn) / footprints 495-501 of 2523")
	)
	(layers
		(0 "F.Cu" signal "TOP")
		(4 "In1.Cu" signal "L2GND")
		(6 "In2.Cu" signal "L3")
		(8 "In3.Cu" signal "L4VCC")
		(10 "In4.Cu" signal "L5VCC")
		(12 "In5.Cu" signal "L6")
		(14 "In6.Cu" signal "L7GND")
		(2 "B.Cu" signal "BOTTOM")
		(9 "F.Adhes" user "F.Adhesive")
		(11 "B.Adhes" user "B.Adhesive")
		(13 "F.Paste" user "Package Geometry/Pastemask Top")
		(15 "B.Paste" user "Package Geometry/Pastemask Bottom")
		(5 "F.SilkS" user "Ref Des/Silkscreen Top")
		(7 "B.SilkS" user "Ref Des/Silkscreen Bottom")
		(1 "F.Mask" user "Board Geometry/Soldermask Top")
		(3 "B.Mask" user "Board Geometry/Soldermask Bottom")
		(17 "Dwgs.User" user "User.Drawings")
		(19 "Cmts.User" user "User.Comments")
		(21 "Eco1.User" user "User.Eco1")
		(23 "Eco2.User" user "User.Eco2")
		(25 "Edge.Cuts" user "Board Geometry/Outline")
		(27 "Margin" user)
		(31 "F.CrtYd" user "Package Geometry/Place Bound Top")
		(29 "B.CrtYd" user "Package Geometry/Place Bound Bottom")
		(35 "F.Fab" user "Ref Des/Assembly Top")
		(33 "B.Fab" user "Ref Des/Assembly Bottom")
	)
	(footprint ""
		(layer "F.Cu")
		(at 279.302972 -188.507116)
		(property "Reference" "OSC1"
			(at 0 0 0)
			(layer "F.SilkS")
			(hide yes)
			(effects
				(font
					(size 1.27 1.27)
				)
			)
		)
		(property "Value" "OSC-48MHZ-28-GP"
			(at 0.0127 -2.7686 0)
			(unlocked yes)
			(layer "F.Fab")
			(hide yes)
			(effects
				(font
					(size 1.016 1.016)
					(thickness 0.1524)
				)
			)
		)
		(property "Device Type" "OSC-3225-4P-3H48"
			(at 0.0127 -4.2926 0)
			(unlocked yes)
			(layer "F.Fab")
			(hide yes)
			(effects
				(font
					(size 1.016 1.016)
					(thickness 0.1524)
				)
			)
		)
		(duplicate_pad_numbers_are_jumpers no)
		(fp_line
			(start -2.2352 1.6256)
			(end -2.2352 0.635)
			(stroke
				(width 0.3302)
				(type default)
			)
			(layer "F.SilkS")
		)
		(fp_line
			(start -2.1209 -1.5367)
			(end 2.1209 -1.5367)
			(stroke
				(width 0.1524)
				(type default)
			)
			(layer "F.SilkS")
		)
		(fp_line
			(start -2.1209 1.5367)
			(end -2.1209 -1.5367)
			(stroke
				(width 0.1524)
				(type default)
			)
			(layer "F.SilkS")
		)
		(fp_line
			(start -1.3208 1.6256)
			(end -2.2352 1.6256)
			(stroke
				(width 0.3302)
				(type default)
			)
			(layer "F.SilkS")
		)
		(fp_line
			(start 2.1209 -1.5367)
			(end 2.1209 1.5367)
			(stroke
				(width 0.1524)
				(type default)
			)
			(layer "F.SilkS")
		)
		(fp_line
			(start 2.1209 1.5367)
			(end -2.1209 1.5367)
			(stroke
				(width 0.1524)
				(type default)
			)
			(layer "F.SilkS")
		)
		(fp_poly
			(pts
				(xy -2.8321 1.459992) (xy -2.8321 0.189992) (xy -2.1971 0.824992)
			)
			(stroke
				(width 0)
				(type default)
			)
			(fill yes)
			(layer "F.SilkS")
		)
		(fp_rect
			(start -1.6002 1.2446)
			(end 1.6002 -1.2446)
			(stroke
				(width 0)
				(type default)
			)
			(fill no)
			(layer "F.CrtYd")
		)
		(fp_poly
			(pts
				(xy -2.3749 1.7907) (xy -2.3749 -1.7907) (xy 2.3749 -1.7907) (xy 2.3749 1.7907) (xy 1.6002 1.7907)
				(xy 1.6002 -1.2446) (xy -1.6002 -1.2446) (xy -1.6002 1.2446) (xy 1.59512 1.2446) (xy 1.59512 1.7907)
			)
			(stroke
				(width 0)
				(type default)
			)
			(fill no)
			(layer "F.CrtYd")
		)
		(fp_rect
			(start -2.3749 1.7907)
			(end 2.3749 -1.7907)
			(stroke
				(width 0)
				(type default)
			)
			(fill no)
			(layer "F.Fab")
		)
		(pad "1" smd rect
			(at -1.171448 0.824992)
			(size 1.397 0.9144)
			(layers "F.Cu" "F.Mask" "F.Paste")
			(net "OSC2_CONT")
		)
		(pad "2" smd rect
			(at 1.171448 0.824992)
			(size 1.397 0.9144)
			(layers "F.Cu" "F.Mask" "F.Paste")
			(net "GND")
		)
		(pad "3" smd rect
			(at 1.171448 -0.824992)
			(size 1.397 0.9144)
			(layers "F.Cu" "F.Mask" "F.Paste")
			(net "OSC2_OUT")
		)
		(pad "4" smd rect
			(at -1.171448 -0.824992)
			(size 1.397 0.9144)
			(layers "F.Cu" "F.Mask" "F.Paste")
			(net "P3V3_STBY")
		)
		(zone
			(layer "F.Cu")
			(hatch none 0.5)
			(connect_pads
				(clearance 0)
			)
			(min_thickness 0.25)
			(keepout
				(tracks not_allowed)
				(vias allowed)
				(pads allowed)
				(copperpour not_allowed)
				(footprints allowed)
			)
			(placement
				(enabled no)
				(sheetname "")
			)
			(fill
				(thermal_gap 0.5)
				(thermal_bridge_width 0.5)
				(island_removal_mode 0)
			)
			(polygon
				(pts
					(xy 279.155144 -188.464444) (xy 279.4508 -188.464444) (xy 279.4508 -188.549788) (xy 279.155144 -188.549788)
				)
			)
		)
		(zone
			(layer "F.Cu")
			(hatch none 0.5)
			(connect_pads
				(clearance 0)
			)
			(min_thickness 0.25)
			(keepout
				(tracks allowed)
				(vias not_allowed)
				(pads allowed)
				(copperpour not_allowed)
				(footprints allowed)
			)
			(placement
				(enabled no)
				(sheetname "")
			)
			(fill
				(thermal_gap 0.5)
				(thermal_bridge_width 0.5)
				(island_removal_mode 0)
			)
			(polygon
				(pts
					(xy 278.830024 -187.224924) (xy 278.830024 -188.139324) (xy 277.433024 -188.139324) (xy 277.433024 -188.874908)
					(xy 278.830024 -188.874908) (xy 278.830024 -189.789308) (xy 279.77592 -189.789308) (xy 279.77592 -188.874908)
					(xy 281.17292 -188.874908) (xy 281.17292 -188.139324) (xy 279.77592 -188.139324) (xy 279.77592 -187.224924)
				)
			)
		)
	)
	(footprint ""
		(layer "F.Cu")
		(at 294.513 -157.988)
		(property "Reference" "R679"
			(at 0 0 0)
			(layer "F.SilkS")
			(hide yes)
			(effects
				(font
					(size 1.27 1.27)
				)
			)
		)
		(property "Value" "0R2J-2-GP"
			(at 0.064008 -3.993896 0)
			(unlocked yes)
			(layer "F.Fab")
			(hide yes)
			(effects
				(font
					(size 1.016 1.016)
					(thickness 0.1524)
				)
			)
		)
		(property "Device Type" "R402H16"
			(at 0.064008 -5.517896 0)
			(unlocked yes)
			(layer "F.Fab")
			(hide yes)
			(effects
				(font
					(size 1.016 1.016)
					(thickness 0.1524)
				)
			)
		)
		(duplicate_pad_numbers_are_jumpers no)
		(fp_line
			(start -0.508 -0.9398)
			(end -0.508 0.9398)
			(stroke
				(width 0.1524)
				(type default)
			)
			(layer "F.SilkS")
		)
		(fp_line
			(start 0.508 -0.9398)
			(end -0.508 -0.9398)
			(stroke
				(width 0.1524)
				(type default)
			)
			(layer "F.SilkS")
		)
		(fp_rect
			(start -0.508 0.9398)
			(end 0.508 -0.9398)
			(stroke
				(width 0)
				(type default)
			)
			(fill no)
			(layer "F.CrtYd")
		)
		(fp_rect
			(start -0.508 0.9398)
			(end 0.508 -0.9398)
			(stroke
				(width 0)
				(type default)
			)
			(fill no)
			(layer "F.Fab")
		)
		(pad "1" smd custom
			(at 0 -0.4445)
			(size 0.1397 0.1397)
			(layers "F.Cu" "F.Mask" "F.Paste")
			(net "BMC_RXCK_R")
			(options
				(clearance outline)
				(anchor circle)
			)
			(primitives
				(gr_poly
					(pts
						(arc
							(start -0.1778 -0.2794)
							(mid -0.249642 -0.249642)
							(end -0.2794 -0.1778)
						)
						(arc
							(start -0.2794 0.1778)
							(mid -0.249642 0.249642)
							(end -0.1778 0.2794)
						)
						(arc
							(start 0.1778 0.2794)
							(mid 0.249642 0.249642)
							(end 0.2794 0.1778)
						)
						(arc
							(start 0.2794 -0.1778)
							(mid 0.249642 -0.249642)
							(end 0.1778 -0.2794)
						)
					)
					(width 0)
					(fill yes)
				)
			)
		)
		(pad "2" smd custom
			(at 0 0.4445)
			(size 0.1397 0.1397)
			(layers "F.Cu" "F.Mask" "F.Paste")
			(net "CLK_50M_BMC0")
			(options
				(clearance outline)
				(anchor circle)
			)
			(primitives
				(gr_poly
					(pts
						(arc
							(start -0.1778 -0.2794)
							(mid -0.249642 -0.249642)
							(end -0.2794 -0.1778)
						)
						(arc
							(start -0.2794 0.1778)
							(mid -0.249642 0.249642)
							(end -0.1778 0.2794)
						)
						(arc
							(start 0.1778 0.2794)
							(mid 0.249642 0.249642)
							(end 0.2794 0.1778)
						)
						(arc
							(start 0.2794 -0.1778)
							(mid 0.249642 -0.249642)
							(end 0.1778 -0.2794)
						)
					)
					(width 0)
					(fill yes)
				)
			)
		)
	)
	(footprint ""
		(layer "F.Cu")
		(at 199.205596 -121.558812 180)
		(property "Reference" "PC232"
			(at 0 0 180)
			(layer "F.SilkS")
			(hide yes)
			(effects
				(font
					(size 1.27 1.27)
				)
			)
		)
		(property "Value" "SC1U16V3KX-5GP"
			(at 0 -2.8194 180)
			(unlocked yes)
			(layer "F.Fab")
			(hide yes)
			(effects
				(font
					(size 1.016 1.016)
					(thickness 0.1524)
				)
			)
		)
		(property "Device Type" "C603H36"
			(at 0 -4.3434 180)
			(unlocked yes)
			(layer "F.Fab")
			(hide yes)
			(effects
				(font
					(size 1.016 1.016)
					(thickness 0.1524)
				)
			)
		)
		(duplicate_pad_numbers_are_jumpers no)
		(fp_line
			(start 0.508 0)
			(end -0.508 0)
			(stroke
				(width 0.2032)
				(type default)
			)
			(layer "F.SilkS")
		)
		(fp_rect
			(start -0.5842 1.3335)
			(end 0.5842 -1.3335)
			(stroke
				(width 0)
				(type default)
			)
			(fill no)
			(layer "F.CrtYd")
		)
		(fp_rect
			(start -0.5842 1.3335)
			(end 0.5842 -1.3335)
			(stroke
				(width 0)
				(type default)
			)
			(fill no)
			(layer "F.Fab")
		)
		(pad "1" smd custom
			(at 0 -0.762 180)
			(size 0.2159 0.2159)
			(layers "F.Cu" "F.Mask" "F.Paste")
			(net "P1V5_E_VRG5")
			(options
				(clearance outline)
				(anchor circle)
			)
			(primitives
				(gr_poly
					(pts
						(arc
							(start -0.3302 -0.4318)
							(mid -0.402042 -0.402042)
							(end -0.4318 -0.3302)
						)
						(arc
							(start -0.4318 0.3302)
							(mid -0.402042 0.402042)
							(end -0.3302 0.4318)
						)
						(arc
							(start 0.3302 0.4318)
							(mid 0.402042 0.402042)
							(end 0.4318 0.3302)
						)
						(arc
							(start 0.4318 -0.3302)
							(mid 0.402042 -0.402042)
							(end 0.3302 -0.4318)
						)
					)
					(width 0)
					(fill yes)
				)
			)
		)
		(pad "2" smd custom
			(at 0 0.762 180)
			(size 0.2159 0.2159)
			(layers "F.Cu" "F.Mask" "F.Paste")
			(net "GND")
			(options
				(clearance outline)
				(anchor circle)
			)
			(primitives
				(gr_poly
					(pts
						(arc
							(start -0.3302 -0.4318)
							(mid -0.402042 -0.402042)
							(end -0.4318 -0.3302)
						)
						(arc
							(start -0.4318 0.3302)
							(mid -0.402042 0.402042)
							(end -0.3302 0.4318)
						)
						(arc
							(start 0.3302 0.4318)
							(mid 0.402042 0.402042)
							(end 0.4318 0.3302)
						)
						(arc
							(start 0.4318 -0.3302)
							(mid 0.402042 -0.402042)
							(end 0.3302 -0.4318)
						)
					)
					(width 0)
					(fill yes)
				)
			)
		)
	)
	(footprint ""
		(layer "F.Cu")
		(at 85.071966 -61.341 -90)
		(property "Reference" "SC887"
			(at 0 0 270)
			(layer "F.SilkS")
			(hide yes)
			(effects
				(font
					(size 1.27 1.27)
				)
			)
		)
		(property "Value" "SC12P50V2JN-3GP"
			(at 1.1811 -2.7051 270)
			(unlocked yes)
			(layer "F.Fab")
			(hide yes)
			(effects
				(font
					(size 1.016 1.016)
					(thickness 0.1524)
				)
			)
		)
		(property "Device Type" "C402H24"
			(at 1.1811 -4.2291 270)
			(unlocked yes)
			(layer "F.Fab")
			(hide yes)
			(effects
				(font
					(size 1.016 1.016)
					(thickness 0.1524)
				)
			)
		)
		(duplicate_pad_numbers_are_jumpers no)
		(fp_rect
			(start -0.4318 0.9525)
			(end 0.4318 -0.9525)
			(stroke
				(width 0)
				(type default)
			)
			(fill no)
			(layer "F.CrtYd")
		)
		(fp_rect
			(start -0.4318 0.9525)
			(end 0.4318 -0.9525)
			(stroke
				(width 0)
				(type default)
			)
			(fill no)
			(layer "F.Fab")
		)
		(pad "1" smd custom
			(at 0 -0.4445 270)
			(size 0.1524 0.1524)
			(layers "F.Cu" "F.Mask" "F.Paste")
			(net "IOC_REF_CLK_P")
			(options
				(clearance outline)
				(anchor circle)
			)
			(primitives
				(gr_poly
					(pts
						(arc
							(start 0.3048 -0.2032)
							(mid 0.275042 -0.275042)
							(end 0.2032 -0.3048)
						)
						(arc
							(start -0.2032 -0.3048)
							(mid -0.275042 -0.275042)
							(end -0.3048 -0.2032)
						)
						(arc
							(start -0.3048 0.2032)
							(mid -0.275042 0.275042)
							(end -0.2032 0.3048)
						)
						(arc
							(start 0.2032 0.3048)
							(mid 0.275042 0.275042)
							(end 0.3048 0.2032)
						)
					)
					(width 0)
					(fill yes)
				)
			)
		)
		(pad "2" smd custom
			(at 0 0.4445 270)
			(size 0.1524 0.1524)
			(layers "F.Cu" "F.Mask" "F.Paste")
			(net "GND")
			(options
				(clearance outline)
				(anchor circle)
			)
			(primitives
				(gr_poly
					(pts
						(arc
							(start 0.3048 -0.2032)
							(mid 0.275042 -0.275042)
							(end 0.2032 -0.3048)
						)
						(arc
							(start -0.2032 -0.3048)
							(mid -0.275042 -0.275042)
							(end -0.3048 -0.2032)
						)
						(arc
							(start -0.3048 0.2032)
							(mid -0.275042 0.275042)
							(end -0.2032 0.3048)
						)
						(arc
							(start 0.2032 0.3048)
							(mid 0.275042 0.275042)
							(end 0.3048 0.2032)
						)
					)
					(width 0)
					(fill yes)
				)
			)
		)
	)
	(footprint ""
		(layer "F.Cu")
		(at 117.602 -29.845)
		(property "Reference" "STP41"
			(at 0 0 0)
			(layer "F.SilkS")
			(hide yes)
			(effects
				(font
					(size 1.27 1.27)
				)
			)
		)
		(property "Value" "TPAD28"
			(at 0.0127 -1.8034 0)
			(unlocked yes)
			(layer "F.Fab")
			(hide yes)
			(effects
				(font
					(size 1.016 1.016)
					(thickness 0.1524)
				)
			)
		)
		(property "Device Type" "TPAD28"
			(at 0.0127 -3.3274 0)
			(unlocked yes)
			(layer "F.Fab")
			(hide yes)
			(effects
				(font
					(size 1.016 1.016)
					(thickness 0.1524)
				)
			)
		)
		(duplicate_pad_numbers_are_jumpers no)
		(fp_poly
			(pts
				(arc
					(start 0.3556 0)
					(mid -0.3556 0)
					(end 0.3556 0)
				)
			)
			(stroke
				(width 0)
				(type default)
			)
			(fill no)
			(layer "F.CrtYd")
		)
		(fp_poly
			(pts
				(arc
					(start 0.6096 0)
					(mid -0.6096 0)
					(end 0.6096 0)
				)
			)
			(stroke
				(width 0)
				(type default)
			)
			(fill no)
			(layer "F.Fab")
		)
		(pad "1" smd circle
			(at 0 0)
			(size 0.7112 0.7112)
			(layers "F.Cu" "F.Mask" "F.Paste")
			(net "SYS_HALT1#")
		)
	)
	(footprint ""
		(layer "F.Cu")
		(at 6.300216 -213.54288 90)
		(property "Reference" "R621"
			(at 0 0 90)
			(layer "F.SilkS")
			(hide yes)
			(effects
				(font
					(size 1.27 1.27)
				)
			)
		)
		(property "Value" "0R2J-2-GP"
			(at 0.064008 -3.993896 90)
			(unlocked yes)
			(layer "F.Fab")
			(hide yes)
			(effects
				(font
					(size 1.016 1.016)
					(thickness 0.1524)
				)
			)
		)
		(property "Device Type" "R402H16"
			(at 0.064008 -5.517896 90)
			(unlocked yes)
			(layer "F.Fab")
			(hide yes)
			(effects
				(font
					(size 1.016 1.016)
					(thickness 0.1524)
				)
			)
		)
		(duplicate_pad_numbers_are_jumpers no)
		(fp_line
			(start 0.508 -0.9398)
			(end -0.508 -0.9398)
			(stroke
				(width 0.1524)
				(type default)
			)
			(layer "F.SilkS")
		)
		(fp_line
			(start -0.508 -0.9398)
			(end -0.508 0.9398)
			(stroke
				(width 0.1524)
				(type default)
			)
			(layer "F.SilkS")
		)
		(fp_rect
			(start -0.508 0.9398)
			(end 0.508 -0.9398)
			(stroke
				(width 0)
				(type default)
			)
			(fill no)
			(layer "F.CrtYd")
		)
		(fp_rect
			(start -0.508 0.9398)
			(end 0.508 -0.9398)
			(stroke
				(width 0)
				(type default)
			)
			(fill no)
			(layer "F.Fab")
		)
		(pad "1" smd custom
			(at 0 -0.4445 90)
			(size 0.1397 0.1397)
			(layers "F.Cu" "F.Mask" "F.Paste")
			(net "BUS_SW_EN")
			(options
				(clearance outline)
				(anchor circle)
			)
			(primitives
				(gr_poly
					(pts
						(arc
							(start -0.1778 -0.2794)
							(mid -0.249642 -0.249642)
							(end -0.2794 -0.1778)
						)
						(arc
							(start -0.2794 0.1778)
							(mid -0.249642 0.249642)
							(end -0.1778 0.2794)
						)
						(arc
							(start 0.1778 0.2794)
							(mid 0.249642 0.249642)
							(end 0.2794 0.1778)
						)
						(arc
							(start 0.2794 -0.1778)
							(mid 0.249642 -0.249642)
							(end 0.1778 -0.2794)
						)
					)
					(width 0)
					(fill yes)
				)
			)
		)
		(pad "2" smd custom
			(at 0 0.4445 90)
			(size 0.1397 0.1397)
			(layers "F.Cu" "F.Mask" "F.Paste")
			(net "PRSNT_AND_3")
			(options
				(clearance outline)
				(anchor circle)
			)
			(primitives
				(gr_poly
					(pts
						(arc
							(start -0.1778 -0.2794)
							(mid -0.249642 -0.249642)
							(end -0.2794 -0.1778)
						)
						(arc
							(start -0.2794 0.1778)
							(mid -0.249642 0.249642)
							(end -0.1778 0.2794)
						)
						(arc
							(start 0.1778 0.2794)
							(mid 0.249642 0.249642)
							(end 0.2794 0.1778)
						)
						(arc
							(start 0.2794 -0.1778)
							(mid 0.249642 -0.249642)
							(end 0.1778 -0.2794)
						)
					)
					(width 0)
					(fill yes)
				)
			)
		)
	)
	(footprint ""
		(layer "F.Cu")
		(at 118.37797 -114.3 180)
		(property "Reference" "SC1071"
			(at 0 0 180)
			(layer "F.SilkS")
			(hide yes)
			(effects
				(font
					(size 1.27 1.27)
				)
			)
		)
		(property "Value" "SCD01U10V1KX-GP"
			(at -2.8321 -1.7399 180)
			(unlocked yes)
			(layer "F.Fab")
			(hide yes)
			(effects
				(font
					(size 1.016 1.016)
					(thickness 0.1524)
				)
			)
		)
		(property "Device Type" "C0201H13"
			(at -2.8321 -3.2639 180)
			(unlocked yes)
			(layer "F.Fab")
			(hide yes)
			(effects
				(font
					(size 1.016 1.016)
					(thickness 0.1524)
				)
			)
		)
		(duplicate_pad_numbers_are_jumpers no)
		(fp_rect
			(start -0.2794 0.6477)
			(end 0.2794 -0.6477)
			(stroke
				(width 0)
				(type default)
			)
			(fill no)
			(layer "F.CrtYd")
		)
		(fp_rect
			(start -0.2794 0.6477)
			(end 0.2794 -0.6477)
			(stroke
				(width 0)
				(type default)
			)
			(fill no)
			(layer "F.Fab")
		)
		(pad "1" smd custom
			(at 0 -0.2794 180)
			(size 0.0762 0.0762)
			(layers "F.Cu" "F.Mask" "F.Paste")
			(net "SAS_HDD_TX2_P")
			(options
				(clearance outline)
				(anchor circle)
			)
			(primitives
				(gr_poly
					(pts
						(arc
							(start 0.1524 -0.127)
							(mid 0.137521 -0.162921)
							(end 0.1016 -0.1778)
						)
						(arc
							(start -0.1016 -0.1778)
							(mid -0.137521 -0.162921)
							(end -0.1524 -0.127)
						)
						(arc
							(start -0.1524 0.127)
							(mid -0.137521 0.162921)
							(end -0.1016 0.1778)
						)
						(arc
							(start 0.1016 0.1778)
							(mid 0.137521 0.162921)
							(end 0.1524 0.127)
						)
					)
					(width 0)
					(fill yes)
				)
			)
		)
		(pad "2" smd custom
			(at 0 0.2794 180)
			(size 0.0762 0.0762)
			(layers "F.Cu" "F.Mask" "F.Paste")
			(net "SAS_EXP_GF_TX_DP6")
			(options
				(clearance outline)
				(anchor circle)
			)
			(primitives
				(gr_poly
					(pts
						(arc
							(start 0.1524 -0.127)
							(mid 0.137521 -0.162921)
							(end 0.1016 -0.1778)
						)
						(arc
							(start -0.1016 -0.1778)
							(mid -0.137521 -0.162921)
							(end -0.1524 -0.127)
						)
						(arc
							(start -0.1524 0.127)
							(mid -0.137521 0.162921)
							(end -0.1016 0.1778)
						)
						(arc
							(start 0.1016 0.1778)
							(mid 0.137521 0.162921)
							(end 0.1524 0.127)
						)
					)
					(width 0)
					(fill yes)
				)
			)
		)
	)
)
